# S9S_MB_2U (Grand Teton) — schematic netlist excerpt (pin names and nets, part order shuffled) for the footprints in the layout excerpt that follows; sources: Cadence DE-HDL packaged netlist, KiCad conversion of 03242023_DA0F0TMBIJ0_F0T_Motherboard_J_brd_V01_OCP.brd

R4399  Q_RES  33.2 1% CHIP  pkg 0402LF  page 121 : A = H_CPU0_THERMTRIP_VT_N ; B = H_CPU0_THERMTRIP_LVC1_N
R3756  Q_RES  33.2 1% CHIP  pkg 0402LF  page 171 : A = SMB_INA230_2_3V3AUX_SDA_R ; B = SMB_INA230_2_3V3AUX_SDA_R1

(kicad_pcb
	(version 20260206)
	(generator "pcbnew")
	(generator_version "10.0")
	(general
		(thickness 1.6)
		(legacy_teardrops no)
	)
	(paper "A4")
	(title_block
		(title "03242023_DA0F0TMBIJ0_F0T_Motherboard_J_brd_V01_OCP.brd")
		(comment 1 "Grand Teton / footprints 1981-1982 of 6105")
	)
	(layers
		(0 "F.Cu" signal "TOP")
		(4 "In1.Cu" signal "GND")
		(6 "In2.Cu" signal "IN1")
		(8 "In3.Cu" signal "GND1")
		(10 "In4.Cu" signal "IN2")
		(12 "In5.Cu" signal "GND2")
		(14 "In6.Cu" signal "IN3")
		(16 "In7.Cu" signal "GND3")
		(18 "In8.Cu" signal "VCC")
		(20 "In9.Cu" signal "VCC1")
		(22 "In10.Cu" signal "GND4")
		(24 "In11.Cu" signal "IN4")
		(26 "In12.Cu" signal "GND5")
		(28 "In13.Cu" signal "IN5")
		(30 "In14.Cu" signal "GND6")
		(32 "In15.Cu" signal "IN6")
		(34 "In16.Cu" signal "GND7")
		(2 "B.Cu" signal "BOTTOM")
		(9 "F.Adhes" user "F.Adhesive")
		(11 "B.Adhes" user "B.Adhesive")
		(13 "F.Paste" user "Package Geometry/Pastemask Top")
		(15 "B.Paste" user "Package Geometry/Pastemask Bottom")
		(5 "F.SilkS" user "Ref Des/Silkscreen Top")
		(7 "B.SilkS" user "Ref Des/Silkscreen Bottom")
		(1 "F.Mask" user "Board Geometry/Soldermask Top")
		(3 "B.Mask" user "Board Geometry/Soldermask Bottom")
		(17 "Dwgs.User" user "User.Drawings")
		(19 "Cmts.User" user "User.Comments")
		(21 "Eco1.User" user "User.Eco1")
		(23 "Eco2.User" user "User.Eco2")
		(25 "Edge.Cuts" user "Board Geometry/Outline")
		(27 "Margin" user)
		(31 "F.CrtYd" user "Package Geometry/Place Bound Top")
		(29 "B.CrtYd" user "Package Geometry/Place Bound Bottom")
		(35 "F.Fab" user "Ref Des/Assembly Top")
		(33 "B.Fab" user "Ref Des/Assembly Bottom")
	)
	(footprint ""
		(layer "F.Cu")
		(at 123.62688 -92.674948 -90)
		(property "Reference" "R4399"
			(at 0 0 270)
			(layer "F.SilkS")
			(hide yes)
			(effects
				(font
					(size 1.27 1.27)
				)
			)
		)
		(property "Value" ""
			(at 0 0 270)
			(layer "F.Fab")
			(effects
				(font
					(size 1.27 1.27)
				)
			)
		)
		(duplicate_pad_numbers_are_jumpers no)
		(fp_line
			(start -0.7874 0.4064)
			(end -0.7874 -0.4064)
			(stroke
				(width 0.1524)
				(type default)
			)
			(layer "F.SilkS")
		)
		(fp_line
			(start 0.7874 0.4064)
			(end -0.7874 0.4064)
			(stroke
				(width 0.1524)
				(type default)
			)
			(layer "F.SilkS")
		)
		(fp_line
			(start -0.7874 -0.4064)
			(end 0.7874 -0.4064)
			(stroke
				(width 0.1524)
				(type default)
			)
			(layer "F.SilkS")
		)
		(fp_line
			(start 0.7874 -0.4064)
			(end 0.7874 0.4064)
			(stroke
				(width 0.1524)
				(type default)
			)
			(layer "F.SilkS")
		)
		(fp_line
			(start -0.67945 0.3048)
			(end -0.67945 -0.305054)
			(stroke
				(width 0.1)
				(type default)
			)
			(layer "F.Fab")
		)
		(fp_line
			(start -0.12065 0.3048)
			(end -0.67945 0.3048)
			(stroke
				(width 0.1)
				(type default)
			)
			(layer "F.Fab")
		)
		(fp_line
			(start 0.120396 0.3048)
			(end 0.120396 0.2794)
			(stroke
				(width 0.1)
				(type default)
			)
			(layer "F.Fab")
		)
		(fp_line
			(start 0.67945 0.3048)
			(end 0.120396 0.3048)
			(stroke
				(width 0.1)
				(type default)
			)
			(layer "F.Fab")
		)
		(fp_line
			(start -0.12065 0.2794)
			(end -0.12065 0.3048)
			(stroke
				(width 0.1)
				(type default)
			)
			(layer "F.Fab")
		)
		(fp_line
			(start 0.120396 0.2794)
			(end -0.12065 0.2794)
			(stroke
				(width 0.1)
				(type default)
			)
			(layer "F.Fab")
		)
		(fp_line
			(start -0.12065 -0.2794)
			(end 0.12065 -0.2794)
			(stroke
				(width 0.1)
				(type default)
			)
			(layer "F.Fab")
		)
		(fp_line
			(start 0.12065 -0.2794)
			(end 0.12065 -0.3048)
			(stroke
				(width 0.1)
				(type default)
			)
			(layer "F.Fab")
		)
		(fp_line
			(start 0.12065 -0.3048)
			(end 0.67945 -0.3048)
			(stroke
				(width 0.1)
				(type default)
			)
			(layer "F.Fab")
		)
		(fp_line
			(start 0.67945 -0.3048)
			(end 0.67945 0.3048)
			(stroke
				(width 0.1)
				(type default)
			)
			(layer "F.Fab")
		)
		(fp_line
			(start -0.67945 -0.305054)
			(end -0.12065 -0.305054)
			(stroke
				(width 0.1)
				(type default)
			)
			(layer "F.Fab")
		)
		(fp_line
			(start -0.12065 -0.305054)
			(end -0.12065 -0.2794)
			(stroke
				(width 0.1)
				(type default)
			)
			(layer "F.Fab")
		)
		(pad "1" smd circle
			(at -0.40005 0 270)
			(size 0 0)
			(layers "F.Cu" "F.Mask" "F.Paste")
			(net "H_CPU0_THERMTRIP_VT_N")
		)
		(pad "2" smd circle
			(at 0.40005 0 270)
			(size 0 0)
			(layers "F.Cu" "F.Mask" "F.Paste")
			(net "H_CPU0_THERMTRIP_LVC1_N")
		)
	)
	(footprint ""
		(layer "F.Cu")
		(at 213.41588 -50.637948 90)
		(property "Reference" "R3756"
			(at 0 0 90)
			(layer "F.SilkS")
			(hide yes)
			(effects
				(font
					(size 1.27 1.27)
				)
			)
		)
		(property "Value" ""
			(at 0 0 90)
			(layer "F.Fab")
			(effects
				(font
					(size 1.27 1.27)
				)
			)
		)
		(duplicate_pad_numbers_are_jumpers no)
		(fp_line
			(start 0.7874 -0.4064)
			(end 0.7874 0.4064)
			(stroke
				(width 0.1524)
				(type default)
			)
			(layer "F.SilkS")
		)
		(fp_line
			(start -0.7874 -0.4064)
			(end 0.7874 -0.4064)
			(stroke
				(width 0.1524)
				(type default)
			)
			(layer "F.SilkS")
		)
		(fp_line
			(start 0.7874 0.4064)
			(end -0.7874 0.4064)
			(stroke
				(width 0.1524)
				(type default)
			)
			(layer "F.SilkS")
		)
		(fp_line
			(start -0.7874 0.4064)
			(end -0.7874 -0.4064)
			(stroke
				(width 0.1524)
				(type default)
			)
			(layer "F.SilkS")
		)
		(fp_line
			(start -0.12065 -0.305054)
			(end -0.12065 -0.2794)
			(stroke
				(width 0.1)
				(type default)
			)
			(layer "F.Fab")
		)
		(fp_line
			(start -0.67945 -0.305054)
			(end -0.12065 -0.305054)
			(stroke
				(width 0.1)
				(type default)
			)
			(layer "F.Fab")
		)
		(fp_line
			(start 0.67945 -0.3048)
			(end 0.67945 0.3048)
			(stroke
				(width 0.1)
				(type default)
			)
			(layer "F.Fab")
		)
		(fp_line
			(start 0.12065 -0.3048)
			(end 0.67945 -0.3048)
			(stroke
				(width 0.1)
				(type default)
			)
			(layer "F.Fab")
		)
		(fp_line
			(start 0.12065 -0.2794)
			(end 0.12065 -0.3048)
			(stroke
				(width 0.1)
				(type default)
			)
			(layer "F.Fab")
		)
		(fp_line
			(start -0.12065 -0.2794)
			(end 0.12065 -0.2794)
			(stroke
				(width 0.1)
				(type default)
			)
			(layer "F.Fab")
		)
		(fp_line
			(start 0.120396 0.2794)
			(end -0.12065 0.2794)
			(stroke
				(width 0.1)
				(type default)
			)
			(layer "F.Fab")
		)
		(fp_line
			(start -0.12065 0.2794)
			(end -0.12065 0.3048)
			(stroke
				(width 0.1)
				(type default)
			)
			(layer "F.Fab")
		)
		(fp_line
			(start 0.67945 0.3048)
			(end 0.120396 0.3048)
			(stroke
				(width 0.1)
				(type default)
			)
			(layer "F.Fab")
		)
		(fp_line
			(start 0.120396 0.3048)
			(end 0.120396 0.2794)
			(stroke
				(width 0.1)
				(type default)
			)
			(layer "F.Fab")
		)
		(fp_line
			(start -0.12065 0.3048)
			(end -0.67945 0.3048)
			(stroke
				(width 0.1)
				(type default)
			)
			(layer "F.Fab")
		)
		(fp_line
			(start -0.67945 0.3048)
			(end -0.67945 -0.305054)
			(stroke
				(width 0.1)
				(type default)
			)
			(layer "F.Fab")
		)
		(pad "1" smd circle
			(at -0.40005 0 90)
			(size 0 0)
			(layers "F.Cu" "F.Mask" "F.Paste")
			(net "SMB_INA230_2_3V3AUX_SDA_R")
		)
		(pad "2" smd circle
			(at 0.40005 0 90)
			(size 0 0)
			(layers "F.Cu" "F.Mask" "F.Paste")
			(net "SMB_INA230_2_3V3AUX_SDA_R1")
		)
	)
)
